# TIMECARD (Time Appliance Project (Time Card)) — schematic netlist excerpt (pin names and nets, part order shuffled) for the footprints in the layout excerpt that follows; sources: Cadence DE-HDL packaged netlist, KiCad conversion of R4006-B0001-02_R01.brd

R279  RESISTOR  330OHM 1%  pkg SMC_0402R_H016  page 26 : \1\ = UNNAMED_14_OPTICAL_I138_A ; \2\ = XP3R3V_FPGA
R76  RESISTOR  33OHM 1%  pkg SMC_0402R_H016  page 20 : \1\ = BNO080_I2C_SDA ; \2\ = R_BNO080_I2C_SDA

(kicad_pcb
	(version 20260206)
	(generator "pcbnew")
	(generator_version "10.0")
	(general
		(thickness 1.6)
		(legacy_teardrops no)
	)
	(paper "A4")
	(title_block
		(title "timecard-production-celestica-r4006 — R4006-B0001-02_R01.brd")
		(comment 1 "Time Appliance Project (Time Card) / footprints 946-947 of 1113")
	)
	(layers
		(0 "F.Cu" signal "TOP")
		(4 "In1.Cu" signal "L02_GND1")
		(6 "In2.Cu" signal "L03_SIG1")
		(8 "In3.Cu" signal "L04_GND2")
		(10 "In4.Cu" signal "L05_VCC1")
		(12 "In5.Cu" signal "L06_VCC2")
		(14 "In6.Cu" signal "L07_GND3")
		(16 "In7.Cu" signal "L08_SIG2")
		(18 "In8.Cu" signal "L09_GND4")
		(2 "B.Cu" signal "BOTTOM")
		(9 "F.Adhes" user "F.Adhesive")
		(11 "B.Adhes" user "B.Adhesive")
		(13 "F.Paste" user "Package Geometry/Pastemask Top")
		(15 "B.Paste" user "Package Geometry/Pastemask Bottom")
		(5 "F.SilkS" user "Ref Des/Silkscreen Top")
		(7 "B.SilkS" user "Ref Des/Silkscreen Bottom")
		(1 "F.Mask" user "Board Geometry/Soldermask Top")
		(3 "B.Mask" user "Board Geometry/Soldermask Bottom")
		(17 "Dwgs.User" user "User.Drawings")
		(19 "Cmts.User" user "User.Comments")
		(21 "Eco1.User" user "User.Eco1")
		(23 "Eco2.User" user "User.Eco2")
		(25 "Edge.Cuts" user "Board Geometry/Outline")
		(27 "Margin" user)
		(31 "F.CrtYd" user "Package Geometry/Place Bound Top")
		(29 "B.CrtYd" user "Package Geometry/Place Bound Bottom")
		(35 "F.Fab" user "Ref Des/Assembly Top")
		(33 "B.Fab" user "Ref Des/Assembly Bottom")
	)
	(footprint ""
		(layer "B.Cu")
		(at 153.0858 -107.696 90)
		(property "Reference" "R279"
			(at 0.508 -2.37617 270)
			(unlocked yes)
			(layer "B.SilkS")
			(effects
				(font
					(size 0.7874 0.5842)
					(thickness 0.1524)
				)
				(justify mirror)
			)
		)
		(property "Value" "VAL*"
			(at -0.02032 2.13233 90)
			(unlocked yes)
			(layer "B.Fab")
			(hide yes)
			(effects
				(font
					(size 0.7874 0.5842)
					(thickness 0.1524)
				)
				(justify mirror)
			)
		)
		(property "Tolerance" "TOL*"
			(at -0.044704 3.05435 90)
			(unlocked yes)
			(layer "Cmts.User")
			(hide yes)
			(effects
				(font
					(size 0.7874 0.5842)
					(thickness 0.1524)
				)
				(justify mirror)
			)
		)
		(property "User Part Number" "PARTNUM*"
			(at -0.02032 4.024884 90)
			(unlocked yes)
			(layer "Cmts.User")
			(hide yes)
			(effects
				(font
					(size 0.7874 0.5842)
					(thickness 0.1524)
				)
				(justify mirror)
			)
		)
		(property "Device Type" "RESISTOR-G155-13300-01,330OHM,A"
			(at -0.008382 1.210564 90)
			(unlocked yes)
			(layer "B.Fab")
			(hide yes)
			(effects
				(font
					(size 0.7874 0.5842)
					(thickness 0.1524)
				)
				(justify mirror)
			)
		)
		(duplicate_pad_numbers_are_jumpers no)
		(fp_line
			(start 1.143 -0.5588)
			(end 1.143 0.5588)
			(stroke
				(width 0.1)
				(type default)
			)
			(layer "B.SilkS")
		)
		(fp_line
			(start -1.143 -0.5588)
			(end 1.143 -0.5588)
			(stroke
				(width 0.1)
				(type default)
			)
			(layer "B.SilkS")
		)
		(fp_line
			(start 1.143 0.5588)
			(end -1.143 0.5588)
			(stroke
				(width 0.1)
				(type default)
			)
			(layer "B.SilkS")
		)
		(fp_line
			(start -1.143 0.5588)
			(end -1.143 -0.5588)
			(stroke
				(width 0.1)
				(type default)
			)
			(layer "B.SilkS")
		)
		(fp_rect
			(start -1.143 -0.5588)
			(end 1.143 0.5588)
			(stroke
				(width 0)
				(type default)
			)
			(fill no)
			(layer "B.CrtYd")
		)
		(fp_line
			(start 0.508 -0.3048)
			(end 0.508 0.3048)
			(stroke
				(width 0.1)
				(type default)
			)
			(layer "B.Fab")
		)
		(fp_line
			(start -0.508 -0.3048)
			(end 0.508 -0.3048)
			(stroke
				(width 0.1)
				(type default)
			)
			(layer "B.Fab")
		)
		(fp_line
			(start 0.508 0.3048)
			(end -0.508 0.3048)
			(stroke
				(width 0.1)
				(type default)
			)
			(layer "B.Fab")
		)
		(fp_line
			(start -0.508 0.3048)
			(end -0.508 -0.3048)
			(stroke
				(width 0.1)
				(type default)
			)
			(layer "B.Fab")
		)
		(pad "1" smd rect
			(at 0.5334 0 270)
			(size 0.7112 0.6096)
			(layers "B.Cu" "B.Mask" "B.Paste")
			(net "UNNAMED_14_OPTICAL_I138_A")
		)
		(pad "2" smd rect
			(at -0.5334 0 270)
			(size 0.7112 0.6096)
			(layers "B.Cu" "B.Mask" "B.Paste")
			(net "XP3R3V_FPGA")
		)
		(zone
			(layer "B.Cu")
			(hatch none 0.5)
			(connect_pads
				(clearance 0)
			)
			(min_thickness 0.25)
			(keepout
				(tracks allowed)
				(vias not_allowed)
				(pads allowed)
				(copperpour not_allowed)
				(footprints allowed)
			)
			(placement
				(enabled no)
				(sheetname "")
			)
			(fill
				(thermal_gap 0.5)
				(thermal_bridge_width 0.5)
				(island_removal_mode 0)
			)
			(polygon
				(pts
					(xy 152.781 -107.6198) (xy 153.3906 -107.6198) (xy 153.3906 -107.7722) (xy 152.781 -107.7722)
				)
			)
		)
	)
	(footprint ""
		(layer "B.Cu")
		(at 87.376 -56.134)
		(property "Reference" "R76"
			(at 1.778 3.08737 0)
			(unlocked yes)
			(layer "B.SilkS")
			(effects
				(font
					(size 0.7874 0.5842)
					(thickness 0.1524)
				)
				(justify mirror)
			)
		)
		(property "Value" "VAL*"
			(at -0.02032 2.13233 0)
			(unlocked yes)
			(layer "B.Fab")
			(hide yes)
			(effects
				(font
					(size 0.7874 0.5842)
					(thickness 0.1524)
				)
				(justify mirror)
			)
		)
		(property "Device Type" "RESISTOR-G155-133R0-01,33OHM,1%"
			(at -0.008382 1.210564 0)
			(unlocked yes)
			(layer "B.Fab")
			(hide yes)
			(effects
				(font
					(size 0.7874 0.5842)
					(thickness 0.1524)
				)
				(justify mirror)
			)
		)
		(property "User Part Number" "PARTNUM*"
			(at -0.02032 4.024884 0)
			(unlocked yes)
			(layer "Cmts.User")
			(hide yes)
			(effects
				(font
					(size 0.7874 0.5842)
					(thickness 0.1524)
				)
				(justify mirror)
			)
		)
		(property "Tolerance" "TOL*"
			(at -0.044704 3.05435 0)
			(unlocked yes)
			(layer "Cmts.User")
			(hide yes)
			(effects
				(font
					(size 0.7874 0.5842)
					(thickness 0.1524)
				)
				(justify mirror)
			)
		)
		(duplicate_pad_numbers_are_jumpers no)
		(fp_line
			(start -1.143 -0.5588)
			(end 1.143 -0.5588)
			(stroke
				(width 0.1)
				(type default)
			)
			(layer "B.SilkS")
		)
		(fp_line
			(start -1.143 0.5588)
			(end -1.143 -0.5588)
			(stroke
				(width 0.1)
				(type default)
			)
			(layer "B.SilkS")
		)
		(fp_line
			(start 1.143 -0.5588)
			(end 1.143 0.5588)
			(stroke
				(width 0.1)
				(type default)
			)
			(layer "B.SilkS")
		)
		(fp_line
			(start 1.143 0.5588)
			(end -1.143 0.5588)
			(stroke
				(width 0.1)
				(type default)
			)
			(layer "B.SilkS")
		)
		(fp_rect
			(start 1.143 -0.5588)
			(end -1.143 0.5588)
			(stroke
				(width 0)
				(type default)
			)
			(fill no)
			(layer "B.CrtYd")
		)
		(fp_line
			(start -0.508 -0.3048)
			(end 0.508 -0.3048)
			(stroke
				(width 0.1)
				(type default)
			)
			(layer "B.Fab")
		)
		(fp_line
			(start -0.508 0.3048)
			(end -0.508 -0.3048)
			(stroke
				(width 0.1)
				(type default)
			)
			(layer "B.Fab")
		)
		(fp_line
			(start 0.508 -0.3048)
			(end 0.508 0.3048)
			(stroke
				(width 0.1)
				(type default)
			)
			(layer "B.Fab")
		)
		(fp_line
			(start 0.508 0.3048)
			(end -0.508 0.3048)
			(stroke
				(width 0.1)
				(type default)
			)
			(layer "B.Fab")
		)
		(pad "1" smd rect
			(at 0.5334 0 180)
			(size 0.7112 0.6096)
			(layers "B.Cu" "B.Mask" "B.Paste")
			(net "BNO080_I2C_SDA")
		)
		(pad "2" smd rect
			(at -0.5334 0 180)
			(size 0.7112 0.6096)
			(layers "B.Cu" "B.Mask" "B.Paste")
			(net "R_BNO080_I2C_SDA")
		)
		(zone
			(layer "B.Cu")
			(hatch none 0.5)
			(connect_pads
				(clearance 0)
			)
			(min_thickness 0.25)
			(keepout
				(tracks allowed)
				(vias not_allowed)
				(pads allowed)
				(copperpour not_allowed)
				(footprints allowed)
			)
			(placement
				(enabled no)
				(sheetname "")
			)
			(fill
				(thermal_gap 0.5)
				(thermal_bridge_width 0.5)
				(island_removal_mode 0)
			)
			(polygon
				(pts
					(xy 87.4522 -56.4388) (xy 87.2998 -56.4388) (xy 87.2998 -55.8292) (xy 87.4522 -55.8292)
				)
			)
		)
	)
)
